(kicad_pcb
	(version 20260206)
	(generator "pcbnew")
	(generator_version "10.0")
	(general
		(thickness 1.6)
		(legacy_teardrops no)
	)
	(paper "A4")
	(title_block
		(title "Bryce Canyon_R.DPB_16317-1_OCP.brd")
		(comment 1 "Bryce Canyon / footprints 997-999 of 2099")
	)
	(layers
		(0 "F.Cu" signal "TOP")
		(4 "In1.Cu" signal "L2GND")
		(6 "In2.Cu" signal "L3")
		(8 "In3.Cu" signal "L4VCC")
		(10 "In4.Cu" signal "L5VCC")
		(12 "In5.Cu" signal "L6")
		(14 "In6.Cu" signal "L7GND")
		(2 "B.Cu" signal "BOTTOM")
		(9 "F.Adhes" user "F.Adhesive")
		(11 "B.Adhes" user "B.Adhesive")
		(13 "F.Paste" user "Package Geometry/Pastemask Top")
		(15 "B.Paste" user "Package Geometry/Pastemask Bottom")
		(5 "F.SilkS" user "Ref Des/Silkscreen Top")
		(7 "B.SilkS" user "Ref Des/Silkscreen Bottom")
		(1 "F.Mask" user "Board Geometry/Soldermask Top")
		(3 "B.Mask" user "Board Geometry/Soldermask Bottom")
		(17 "Dwgs.User" user "User.Drawings")
		(19 "Cmts.User" user "User.Comments")
		(21 "Eco1.User" user "User.Eco1")
		(23 "Eco2.User" user "User.Eco2")
		(25 "Edge.Cuts" user "Board Geometry/Outline")
		(27 "Margin" user)
		(31 "F.CrtYd" user "Package Geometry/Place Bound Top")
		(29 "B.CrtYd" user "Package Geometry/Place Bound Bottom")
		(35 "F.Fab" user "Ref Des/Assembly Top")
		(33 "B.Fab" user "Ref Des/Assembly Bottom")
	)
	(footprint ""
		(layer "F.Cu")
		(at 483.300024 -28.910026 -90)
		(property "Reference" "HDDSAS35"
			(at 0 0 270)
			(layer "F.SilkS")
			(hide yes)
			(effects
				(font
					(size 1.27 1.27)
				)
			)
		)
		(property "Value" "SKT-SAS15P-14P-45-GP"
			(at -20.7645 -8.9789 270)
			(unlocked yes)
			(layer "F.Fab")
			(hide yes)
			(effects
				(font
					(size 1.016 1.016)
					(thickness 0.1524)
				)
			)
		)
		(property "Device Type" "10120818-001C-TRLF"
			(at -20.7645 -10.5029 270)
			(unlocked yes)
			(layer "F.Fab")
			(hide yes)
			(effects
				(font
					(size 1.016 1.016)
					(thickness 0.1524)
				)
			)
		)
		(duplicate_pad_numbers_are_jumpers no)
		(fp_line
			(start 1.651 4.2926)
			(end 1.651 3.0099)
			(stroke
				(width 0.1524)
				(type default)
			)
			(layer "F.SilkS")
		)
		(fp_line
			(start 8.509 4.2926)
			(end 1.651 4.2926)
			(stroke
				(width 0.1524)
				(type default)
			)
			(layer "F.SilkS")
		)
		(fp_line
			(start -23.4188 3.0099)
			(end -23.4188 -3.2512)
			(stroke
				(width 0.1524)
				(type default)
			)
			(layer "F.SilkS")
		)
		(fp_line
			(start 1.651 3.0099)
			(end -23.4188 3.0099)
			(stroke
				(width 0.1524)
				(type default)
			)
			(layer "F.SilkS")
		)
		(fp_line
			(start 8.509 3.0099)
			(end 8.509 4.2926)
			(stroke
				(width 0.1524)
				(type default)
			)
			(layer "F.SilkS")
		)
		(fp_line
			(start 23.4188 3.0099)
			(end 8.509 3.0099)
			(stroke
				(width 0.1524)
				(type default)
			)
			(layer "F.SilkS")
		)
		(fp_line
			(start -23.4188 -3.2512)
			(end 23.4188 -3.2512)
			(stroke
				(width 0.1524)
				(type default)
			)
			(layer "F.SilkS")
		)
		(fp_line
			(start 23.4188 -3.2512)
			(end 23.4188 3.0099)
			(stroke
				(width 0.1524)
				(type default)
			)
			(layer "F.SilkS")
		)
		(fp_line
			(start 15.5067 -3.3401)
			(end 16.2687 -3.3401)
			(stroke
				(width 0.3302)
				(type default)
			)
			(layer "F.SilkS")
		)
		(fp_poly
			(pts
				(xy 15.868904 -3.230372) (xy 16.503904 -3.865372) (xy 15.233904 -3.865372)
			)
			(stroke
				(width 0)
				(type default)
			)
			(fill yes)
			(layer "F.SilkS")
		)
		(fp_poly
			(pts
				(xy -22.8727 -2.7559) (xy 22.8727 -2.7559) (xy 22.8727 2.7559) (xy 8.255 2.7559) (xy 8.255 3.5179)
				(xy 1.905 3.5179) (xy 1.905 2.7559) (xy -22.8727 2.7559)
			)
			(stroke
				(width 0)
				(type default)
			)
			(fill no)
			(layer "F.CrtYd")
		)
		(fp_poly
			(pts
				(xy 1.397 4.5466) (xy 1.397 3.2639) (xy -23.6728 3.2639) (xy -23.6728 -3.5052) (xy 23.6728 -3.5052)
				(xy 23.6728 -0.00635) (xy 22.8727 -0.00635) (xy 22.8727 -2.7559) (xy -22.8727 -2.7559) (xy -22.8727 2.7559)
				(xy 1.905 2.7559) (xy 1.905 3.5179) (xy 8.255 3.5179) (xy 8.255 2.7559) (xy 22.8727 2.7559) (xy 22.8727 0.00635)
				(xy 23.6728 0.00635) (xy 23.6728 3.2639) (xy 8.763 3.2639) (xy 8.763 4.5466)
			)
			(stroke
				(width 0)
				(type default)
			)
			(fill no)
			(layer "F.CrtYd")
		)
		(fp_poly
			(pts
				(xy 1.397 4.5466) (xy 1.397 3.2639) (xy -23.6728 3.2639) (xy -23.6728 -3.5052) (xy 23.6728 -3.5052)
				(xy 23.6728 3.2639) (xy 8.763 3.2639) (xy 8.763 4.5466)
			)
			(stroke
				(width 0)
				(type default)
			)
			(fill no)
			(layer "F.Fab")
		)
		(pad "" np_thru_hole circle
			(at -18.874994 0 270)
			(size 0.254 0.254)
			(drill 1.3462)
			(layers "*.Cu" "*.Mask")
			(clearance 0.9017)
			(thermal_gap 0.9017)
		)
		(pad "" np_thru_hole circle
			(at 18.874994 0 270)
			(size 0.254 0.254)
			(drill 0.9398)
			(layers "*.Cu" "*.Mask")
			(clearance 0.6985)
			(thermal_gap 0.6985)
		)
		(pad "G1" smd rect
			(at 21.874988 0 270)
			(size 2.5908 2.5908)
			(layers "F.Cu" "F.Mask" "F.Paste")
			(net "GND")
		)
		(pad "G2" smd rect
			(at -21.874988 0 270)
			(size 2.5908 2.5908)
			(layers "F.Cu" "F.Mask" "F.Paste")
			(net "GND")
		)
		(pad "P1" smd rect
			(at 1.905 -1.82499 270)
			(size 0.6096 2.3622)
			(layers "F.Cu" "F.Mask" "F.Paste")
			(net "Net_1619")
		)
		(pad "P2" smd rect
			(at 0.635 -1.82499 270)
			(size 0.6096 2.3622)
			(layers "F.Cu" "F.Mask" "F.Paste")
			(net "Net_1620")
		)
		(pad "P3" smd rect
			(at -0.635 -1.82499 270)
			(size 0.6096 2.3622)
			(layers "F.Cu" "F.Mask" "F.Paste")
			(net "Net_1621")
		)
		(pad "P4" smd rect
			(at -1.905 -1.82499 270)
			(size 0.6096 2.3622)
			(layers "F.Cu" "F.Mask" "F.Paste")
			(net "GND")
		)
		(pad "P5" smd rect
			(at -3.175 -1.82499 270)
			(size 0.6096 2.3622)
			(layers "F.Cu" "F.Mask" "F.Paste")
			(net "HDD_PRSNT_35")
		)
		(pad "P6" smd rect
			(at -4.445 -1.82499 270)
			(size 0.6096 2.3622)
			(layers "F.Cu" "F.Mask" "F.Paste")
			(net "GND")
		)
		(pad "P7" smd rect
			(at -5.715 -1.82499 270)
			(size 0.6096 2.3622)
			(layers "F.Cu" "F.Mask" "F.Paste")
			(net "5V_PRE_35")
		)
		(pad "P8" smd rect
			(at -6.985 -1.82499 270)
			(size 0.6096 2.3622)
			(layers "F.Cu" "F.Mask" "F.Paste")
			(net "P5V_HDD35")
		)
		(pad "P9" smd rect
			(at -8.255 -1.82499 270)
			(size 0.6096 2.3622)
			(layers "F.Cu" "F.Mask" "F.Paste")
			(net "P5V_HDD35")
		)
		(pad "P10" smd rect
			(at -9.525 -1.82499 270)
			(size 0.6096 2.3622)
			(layers "F.Cu" "F.Mask" "F.Paste")
			(net "GND")
		)
		(pad "P11" smd rect
			(at -10.795 -1.82499 270)
			(size 0.6096 2.3622)
			(layers "F.Cu" "F.Mask" "F.Paste")
			(net "ACT_HDD_35")
		)
		(pad "P12" smd rect
			(at -12.065 -1.82499 270)
			(size 0.6096 2.3622)
			(layers "F.Cu" "F.Mask" "F.Paste")
			(net "GND")
		)
		(pad "P13" smd rect
			(at -13.335 -1.82499 270)
			(size 0.6096 2.3622)
			(layers "F.Cu" "F.Mask" "F.Paste")
			(net "12V_PRE_35")
		)
		(pad "P14" smd rect
			(at -14.605 -1.82499 270)
			(size 0.6096 2.3622)
			(layers "F.Cu" "F.Mask" "F.Paste")
			(net "P12V_HDD35")
		)
		(pad "P15" smd rect
			(at -15.875 -1.82499 270)
			(size 0.6096 2.3622)
			(layers "F.Cu" "F.Mask" "F.Paste")
			(net "P12V_HDD35")
		)
		(pad "S1" smd rect
			(at 15.875 -1.82499 270)
			(size 0.6096 2.3622)
			(layers "F.Cu" "F.Mask" "F.Paste")
			(net "GND")
		)
		(pad "S2" smd rect
			(at 14.605 -1.82499 270)
			(size 0.6096 2.3622)
			(layers "F.Cu" "F.Mask" "F.Paste")
			(net "SAS_HDD_RX_P35")
		)
		(pad "S3" smd rect
			(at 13.335 -1.82499 270)
			(size 0.6096 2.3622)
			(layers "F.Cu" "F.Mask" "F.Paste")
			(net "SAS_HDD_RX_N35")
		)
		(pad "S4" smd rect
			(at 12.065 -1.82499 270)
			(size 0.6096 2.3622)
			(layers "F.Cu" "F.Mask" "F.Paste")
			(net "GND")
		)
		(pad "S5" smd rect
			(at 10.795 -1.82499 270)
			(size 0.6096 2.3622)
			(layers "F.Cu" "F.Mask" "F.Paste")
			(net "PHY_DRV_B_TO_SCC_B_35_DN")
		)
		(pad "S6" smd rect
			(at 9.525 -1.82499 270)
			(size 0.6096 2.3622)
			(layers "F.Cu" "F.Mask" "F.Paste")
			(net "PHY_DRV_B_TO_SCC_B_35_DP")
		)
		(pad "S7" smd rect
			(at 8.255 -1.82499 270)
			(size 0.6096 2.3622)
			(layers "F.Cu" "F.Mask" "F.Paste")
			(net "GND")
		)
		(pad "S8" smd rect
			(at 7.480046 2.845054 270)
			(size 0.508 2.3622)
			(layers "F.Cu" "F.Mask" "F.Paste")
			(net "GND")
		)
		(pad "S9" smd rect
			(at 6.679946 2.845054 270)
			(size 0.508 2.3622)
			(layers "F.Cu" "F.Mask" "F.Paste")
			(net "Net_460")
		)
		(pad "S10" smd rect
			(at 5.8801 2.845054 270)
			(size 0.508 2.3622)
			(layers "F.Cu" "F.Mask" "F.Paste")
			(net "Net_352")
		)
		(pad "S11" smd rect
			(at 5.08 2.845054 270)
			(size 0.508 2.3622)
			(layers "F.Cu" "F.Mask" "F.Paste")
			(net "GND")
		)
		(pad "S12" smd rect
			(at 4.2799 2.845054 270)
			(size 0.508 2.3622)
			(layers "F.Cu" "F.Mask" "F.Paste")
			(net "Net_388")
		)
		(pad "S13" smd rect
			(at 3.480054 2.845054 270)
			(size 0.508 2.3622)
			(layers "F.Cu" "F.Mask" "F.Paste")
			(net "Net_424")
		)
		(pad "S14" smd rect
			(at 2.679954 2.845054 270)
			(size 0.508 2.3622)
			(layers "F.Cu" "F.Mask" "F.Paste")
			(net "GND")
		)
		(zone
			(layer "F.Cu")
			(hatch none 0.5)
			(connect_pads
				(clearance 0)
			)
			(min_thickness 0.25)
			(keepout
				(tracks allowed)
				(vias not_allowed)
				(pads allowed)
				(copperpour not_allowed)
				(footprints allowed)
			)
			(placement
				(enabled no)
				(sheetname "")
			)
			(fill
				(thermal_gap 0.5)
				(thermal_bridge_width 0.5)
				(island_removal_mode 0)
			)
			(polygon
				(pts
					(xy 486.957624 -45.648626) (xy 479.883724 -45.648626) (xy 479.883724 -52.582826) (xy 480.988624 -52.582826)
					(xy 480.988624 -48.468026) (xy 485.611424 -48.468026) (xy 485.611424 -52.582826) (xy 486.957624 -52.582826)
				)
			)
		)
		(zone
			(layer "F.Cu")
			(hatch none 0.5)
			(connect_pads
				(clearance 0)
			)
			(min_thickness 0.25)
			(keepout
				(tracks not_allowed)
				(vias allowed)
				(pads allowed)
				(copperpour not_allowed)
				(footprints allowed)
			)
			(placement
				(enabled no)
				(sheetname "")
			)
			(fill
				(thermal_gap 0.5)
				(thermal_bridge_width 0.5)
				(island_removal_mode 0)
			)
			(polygon
				(pts
					(xy 486.957624 -45.648626) (xy 479.883724 -45.648626) (xy 479.883724 -52.582826) (xy 480.988624 -52.582826)
					(xy 480.988624 -48.468026) (xy 485.611424 -48.468026) (xy 485.611424 -52.582826) (xy 486.957624 -52.582826)
				)
			)
		)
		(zone
			(layer "F.Cu")
			(hatch none 0.5)
			(connect_pads
				(clearance 0)
			)
			(min_thickness 0.25)
			(keepout
				(tracks not_allowed)
				(vias allowed)
				(pads allowed)
				(copperpour not_allowed)
				(footprints allowed)
			)
			(placement
				(enabled no)
				(sheetname "")
			)
			(fill
				(thermal_gap 0.5)
				(thermal_bridge_width 0.5)
				(island_removal_mode 0)
			)
			(polygon
				(pts
					(xy 486.957624 -12.171426) (xy 479.883724 -12.171426) (xy 479.883724 -5.237226) (xy 480.988624 -5.237226)
					(xy 480.988624 -9.352026) (xy 485.611424 -9.352026) (xy 485.611424 -5.237226) (xy 486.957624 -5.237226)
				)
			)
		)
		(zone
			(layer "F.Cu")
			(hatch none 0.5)
			(connect_pads
				(clearance 0)
			)
			(min_thickness 0.25)
			(keepout
				(tracks allowed)
				(vias not_allowed)
				(pads allowed)
				(copperpour not_allowed)
				(footprints allowed)
			)
			(placement
				(enabled no)
				(sheetname "")
			)
			(fill
				(thermal_gap 0.5)
				(thermal_bridge_width 0.5)
				(island_removal_mode 0)
			)
			(polygon
				(pts
					(xy 486.957624 -12.171426) (xy 479.883724 -12.171426) (xy 479.883724 -5.237226) (xy 480.988624 -5.237226)
					(xy 480.988624 -9.352026) (xy 485.611424 -9.352026) (xy 485.611424 -5.237226) (xy 486.957624 -5.237226)
				)
			)
		)
		(zone
			(layers "F.Cu" "B.Cu" "In1.Cu" "In2.Cu" "In3.Cu" "In4.Cu" "In5.Cu" "In6.Cu")
			(hatch none 0.5)
			(connect_pads
				(clearance 0)
			)
			(min_thickness 0.25)
			(keepout
				(tracks not_allowed)
				(vias allowed)
				(pads allowed)
				(copperpour not_allowed)
				(footprints allowed)
			)
			(placement
				(enabled no)
				(sheetname "")
			)
			(fill
				(thermal_gap 0.5)
				(thermal_bridge_width 0.5)
				(island_removal_mode 0)
			)
			(polygon
				(pts
					(arc
						(start 484.074724 -10.035032)
						(mid 482.525324 -10.035032)
						(end 484.074724 -10.035032)
					)
				)
			)
		)
		(zone
			(layers "F.Cu" "B.Cu" "In1.Cu" "In2.Cu" "In3.Cu" "In4.Cu" "In5.Cu" "In6.Cu")
			(hatch none 0.5)
			(connect_pads
				(clearance 0)
			)
			(min_thickness 0.25)
			(keepout
				(tracks not_allowed)
				(vias allowed)
				(pads allowed)
				(copperpour not_allowed)
				(footprints allowed)
			)
			(placement
				(enabled no)
				(sheetname "")
			)
			(fill
				(thermal_gap 0.5)
				(thermal_bridge_width 0.5)
				(island_removal_mode 0)
			)
			(polygon
				(pts
					(arc
						(start 484.277924 -47.78502)
						(mid 482.322124 -47.78502)
						(end 484.277924 -47.78502)
					)
				)
			)
		)
	)
	(footprint ""
		(layer "F.Cu")
		(at 257.331972 -349.399606 90)
		(property "Reference" "Q201"
			(at 0 0 90)
			(layer "F.SilkS")
			(hide yes)
			(effects
				(font
					(size 1.27 1.27)
				)
			)
		)
		(property "Value" "IRFH8201TRPBF-GP"
			(at -4.2164 -4.3688 90)
			(unlocked yes)
			(layer "F.Fab")
			(hide yes)
			(effects
				(font
					(size 1.016 1.016)
					(thickness 0.1524)
				)
			)
		)
		(property "Device Type" "PPAK-5PH42"
			(at -4.2164 -5.8928 90)
			(unlocked yes)
			(layer "F.Fab")
			(hide yes)
			(effects
				(font
					(size 1.016 1.016)
					(thickness 0.1524)
				)
			)
		)
		(duplicate_pad_numbers_are_jumpers no)
		(fp_line
			(start 2.8956 -2.794)
			(end 2.8956 4.826)
			(stroke
				(width 0.1524)
				(type default)
			)
			(layer "F.SilkS")
		)
		(fp_line
			(start -2.8956 -2.794)
			(end 2.8956 -2.794)
			(stroke
				(width 0.1524)
				(type default)
			)
			(layer "F.SilkS")
		)
		(fp_line
			(start 2.8956 4.826)
			(end -2.8956 4.826)
			(stroke
				(width 0.1524)
				(type default)
			)
			(layer "F.SilkS")
		)
		(fp_line
			(start -2.8956 4.826)
			(end -2.8956 -2.794)
			(stroke
				(width 0.1524)
				(type default)
			)
			(layer "F.SilkS")
		)
		(fp_line
			(start -1.9431 4.9276)
			(end -3.0353 4.9276)
			(stroke
				(width 0.3302)
				(type default)
			)
			(layer "F.SilkS")
		)
		(fp_line
			(start -3.0353 4.9276)
			(end -3.0353 3.9624)
			(stroke
				(width 0.3302)
				(type default)
			)
			(layer "F.SilkS")
		)
		(fp_poly
			(pts
				(xy -2.3622 5.334) (xy -1.4986 5.334) (xy -1.9304 4.9022)
			)
			(stroke
				(width 0)
				(type default)
			)
			(fill yes)
			(layer "F.SilkS")
		)
		(fp_poly
			(pts
				(xy 0.3556 -0.3556) (xy 2.6416 -0.3556) (xy 2.6416 -2.54) (xy 0.3556 -2.54)
			)
			(stroke
				(width 0)
				(type default)
			)
			(fill yes)
			(layer "F.Paste")
		)
		(fp_poly
			(pts
				(xy -2.6416 -0.3556) (xy -0.3556 -0.3556) (xy -0.3556 -2.54) (xy -2.6416 -2.54)
			)
			(stroke
				(width 0)
				(type default)
			)
			(fill yes)
			(layer "F.Paste")
		)
		(fp_poly
			(pts
				(xy 0.3556 2.54) (xy 2.6416 2.54) (xy 2.6416 0.3556) (xy 0.3556 0.3556)
			)
			(stroke
				(width 0)
				(type default)
			)
			(fill yes)
			(layer "F.Paste")
		)
		(fp_poly
			(pts
				(xy -2.6416 2.54) (xy -0.3556 2.54) (xy -0.3556 0.3556) (xy -2.6416 0.3556)
			)
			(stroke
				(width 0)
				(type default)
			)
			(fill yes)
			(layer "F.Paste")
		)
		(fp_rect
			(start -2.5781 3.9878)
			(end 2.5781 -2.1082)
			(stroke
				(width 0)
				(type default)
			)
			(fill no)
			(layer "F.CrtYd")
		)
		(fp_poly
			(pts
				(xy -3.1496 5.08) (xy -3.1496 -3.048) (xy 3.1496 -3.048) (xy 3.1496 3.9751) (xy 2.5781 3.9751) (xy 2.5781 -2.1082)
				(xy -2.5781 -2.1082) (xy -2.5781 3.9878) (xy 3.1496 3.9878) (xy 3.1496 5.08)
			)
			(stroke
				(width 0)
				(type default)
			)
			(fill no)
			(layer "F.CrtYd")
		)
		(fp_rect
			(start -3.1496 5.08)
			(end 3.1496 -3.048)
			(stroke
				(width 0)
				(type default)
			)
			(fill no)
			(layer "F.Fab")
		)
		(pad "1" smd rect
			(at -1.905 3.81 90)
			(size 0.762 1.524)
			(layers "F.Cu" "F.Mask" "F.Paste")
			(net "P12V_B")
		)
		(pad "2" smd rect
			(at -0.635 3.81 90)
			(size 0.762 1.524)
			(layers "F.Cu" "F.Mask" "F.Paste")
			(net "P12V_B")
		)
		(pad "3" smd rect
			(at 0.635 3.81 90)
			(size 0.762 1.524)
			(layers "F.Cu" "F.Mask" "F.Paste")
			(net "P12V_B")
		)
		(pad "4" smd rect
			(at 1.905 3.81 90)
			(size 0.762 1.524)
			(layers "F.Cu" "F.Mask" "F.Paste")
			(net "MB3_12V_CTRL_GATE1")
		)
		(pad "5" smd rect
			(at 0 0 90)
			(size 5.2832 5.08)
			(layers "F.Cu" "F.Mask" "F.Paste")
			(net "MB3_P12V_IN_R")
		)
		(pad "6" smd rect
			(at 0.635 -2.032 90)
			(size 0.0254 0.0254)
			(layers "F.Cu" "F.Mask" "F.Paste")
			(net "MB3_P12V_IN_R")
		)
		(pad "7" smd rect
			(at -0.635 -2.032 90)
			(size 0.0254 0.0254)
			(layers "F.Cu" "F.Mask" "F.Paste")
			(net "MB3_P12V_IN_R")
		)
		(pad "8" smd rect
			(at -1.905 -2.032 90)
			(size 0.0254 0.0254)
			(layers "F.Cu" "F.Mask" "F.Paste")
			(net "MB3_P12V_IN_R")
		)
	)
	(footprint ""
		(layer "F.Cu")
		(at 463.058002 -231.62895 -90)
		(property "Reference" "R1136"
			(at 0 0 270)
			(layer "F.SilkS")
			(hide yes)
			(effects
				(font
					(size 1.27 1.27)
				)
			)
		)
		(property "Value" "0R2J-2-GP"
			(at 0.064008 -3.993896 270)
			(unlocked yes)
			(layer "F.Fab")
			(hide yes)
			(effects
				(font
					(size 1.016 1.016)
					(thickness 0.1524)
				)
			)
		)
		(property "Device Type" "R402H16"
			(at 0.064008 -5.517896 270)
			(unlocked yes)
			(layer "F.Fab")
			(hide yes)
			(effects
				(font
					(size 1.016 1.016)
					(thickness 0.1524)
				)
			)
		)
		(duplicate_pad_numbers_are_jumpers no)
		(fp_line
			(start -0.508 -0.9398)
			(end -0.508 0.9398)
			(stroke
				(width 0.1524)
				(type default)
			)
			(layer "F.SilkS")
		)
		(fp_line
			(start 0.508 -0.9398)
			(end -0.508 -0.9398)
			(stroke
				(width 0.1524)
				(type default)
			)
			(layer "F.SilkS")
		)
		(fp_rect
			(start -0.508 0.9398)
			(end 0.508 -0.9398)
			(stroke
				(width 0)
				(type default)
			)
			(fill no)
			(layer "F.CrtYd")
		)
		(fp_rect
			(start -0.508 0.9398)
			(end 0.508 -0.9398)
			(stroke
				(width 0)
				(type default)
			)
			(fill no)
			(layer "F.Fab")
		)
		(pad "1" smd custom
			(at 0 -0.4445 270)
			(size 0.1397 0.1397)
			(layers "F.Cu" "F.Mask" "F.Paste")
			(net "P12V_B_PGOOD")
			(options
				(clearance outline)
				(anchor circle)
			)
			(primitives
				(gr_poly
					(pts
						(arc
							(start -0.1778 -0.2794)
							(mid -0.249642 -0.249642)
							(end -0.2794 -0.1778)
						)
						(arc
							(start -0.2794 0.1778)
							(mid -0.249642 0.249642)
							(end -0.1778 0.2794)
						)
						(arc
							(start 0.1778 0.2794)
							(mid 0.249642 0.249642)
							(end 0.2794 0.1778)
						)
						(arc
							(start 0.2794 -0.1778)
							(mid 0.249642 -0.249642)
							(end 0.1778 -0.2794)
						)
					)
					(width 0)
					(fill yes)
				)
			)
		)
		(pad "2" smd custom
			(at 0 0.4445 270)
			(size 0.1397 0.1397)
			(layers "F.Cu" "F.Mask" "F.Paste")
			(net "P5V_B_3_EN_R")
			(options
				(clearance outline)
				(anchor circle)
			)
			(primitives
				(gr_poly
					(pts
						(arc
							(start -0.1778 -0.2794)
							(mid -0.249642 -0.249642)
							(end -0.2794 -0.1778)
						)
						(arc
							(start -0.2794 0.1778)
							(mid -0.249642 0.249642)
							(end -0.1778 0.2794)
						)
						(arc
							(start 0.1778 0.2794)
							(mid 0.249642 0.249642)
							(end 0.2794 0.1778)
						)
						(arc
							(start 0.2794 -0.1778)
							(mid 0.249642 -0.249642)
							(end 0.1778 -0.2794)
						)
					)
					(width 0)
					(fill yes)
				)
			)
		)
	)
)
